(kicad_pcb
	(version 20260206)
	(generator "pcbnew")
	(generator_version "10.0")
	(general
		(thickness 1.6)
		(legacy_teardrops no)
	)
	(paper "A4")
	(title_block
		(title "04192023_DAF0TMB3IC0_F0TG_MB_C_brd_V02_OCP.brd")
		(comment 1 "Grand Teton / footprints 7958-7966 of 8354")
	)
	(layers
		(0 "F.Cu" signal "TOP")
		(4 "In1.Cu" signal "GND")
		(6 "In2.Cu" signal "IN1")
		(8 "In3.Cu" signal "GND1")
		(10 "In4.Cu" signal "IN2")
		(12 "In5.Cu" signal "GND2")
		(14 "In6.Cu" signal "IN3")
		(16 "In7.Cu" signal "GND3")
		(18 "In8.Cu" signal "VCC")
		(20 "In9.Cu" signal "VCC1")
		(22 "In10.Cu" signal "GND4")
		(24 "In11.Cu" signal "IN4")
		(26 "In12.Cu" signal "GND5")
		(28 "In13.Cu" signal "IN5")
		(30 "In14.Cu" signal "GND6")
		(32 "In15.Cu" signal "IN6")
		(34 "In16.Cu" signal "GND7")
		(2 "B.Cu" signal "BOTTOM")
		(9 "F.Adhes" user "F.Adhesive")
		(11 "B.Adhes" user "B.Adhesive")
		(13 "F.Paste" user "Package Geometry/Pastemask Top")
		(15 "B.Paste" user "Package Geometry/Pastemask Bottom")
		(5 "F.SilkS" user "Ref Des/Silkscreen Top")
		(7 "B.SilkS" user "Ref Des/Silkscreen Bottom")
		(1 "F.Mask" user "Board Geometry/Soldermask Top")
		(3 "B.Mask" user "Board Geometry/Soldermask Bottom")
		(17 "Dwgs.User" user "User.Drawings")
		(19 "Cmts.User" user "User.Comments")
		(21 "Eco1.User" user "User.Eco1")
		(23 "Eco2.User" user "User.Eco2")
		(25 "Edge.Cuts" user "Board Geometry/Outline")
		(27 "Margin" user)
		(31 "F.CrtYd" user "Package Geometry/Place Bound Top")
		(29 "B.CrtYd" user "Package Geometry/Place Bound Bottom")
		(35 "F.Fab" user "Ref Des/Assembly Top")
		(33 "B.Fab" user "Ref Des/Assembly Bottom")
	)
	(footprint ""
		(layer "B.Cu")
		(at 175.333914 -14.308328 90)
		(property "Reference" "R1385"
			(at 0 0 90)
			(layer "B.SilkS")
			(hide yes)
			(effects
				(font
					(size 1.27 1.27)
				)
				(justify mirror)
			)
		)
		(property "Value" ""
			(at 0 0 90)
			(layer "B.Fab")
			(effects
				(font
					(size 1.27 1.27)
				)
				(justify mirror)
			)
		)
		(duplicate_pad_numbers_are_jumpers no)
		(fp_line
			(start 0.7874 -0.4064)
			(end -0.7874 -0.4064)
			(stroke
				(width 0.1524)
				(type default)
			)
			(layer "B.SilkS")
		)
		(fp_line
			(start -0.7874 -0.4064)
			(end -0.7874 0.4064)
			(stroke
				(width 0.1524)
				(type default)
			)
			(layer "B.SilkS")
		)
		(fp_line
			(start 0.7874 0.4064)
			(end 0.7874 -0.4064)
			(stroke
				(width 0.1524)
				(type default)
			)
			(layer "B.SilkS")
		)
		(fp_line
			(start -0.7874 0.4064)
			(end 0.7874 0.4064)
			(stroke
				(width 0.1524)
				(type default)
			)
			(layer "B.SilkS")
		)
		(fp_line
			(start 0.67945 -0.305054)
			(end 0.12065 -0.305054)
			(stroke
				(width 0.1)
				(type default)
			)
			(layer "B.Fab")
		)
		(fp_line
			(start 0.12065 -0.305054)
			(end 0.12065 -0.2794)
			(stroke
				(width 0.1)
				(type default)
			)
			(layer "B.Fab")
		)
		(fp_line
			(start -0.12065 -0.3048)
			(end -0.67945 -0.3048)
			(stroke
				(width 0.1)
				(type default)
			)
			(layer "B.Fab")
		)
		(fp_line
			(start -0.67945 -0.3048)
			(end -0.67945 0.3048)
			(stroke
				(width 0.1)
				(type default)
			)
			(layer "B.Fab")
		)
		(fp_line
			(start 0.12065 -0.2794)
			(end -0.12065 -0.2794)
			(stroke
				(width 0.1)
				(type default)
			)
			(layer "B.Fab")
		)
		(fp_line
			(start -0.12065 -0.2794)
			(end -0.12065 -0.3048)
			(stroke
				(width 0.1)
				(type default)
			)
			(layer "B.Fab")
		)
		(fp_line
			(start 0.12065 0.2794)
			(end 0.12065 0.3048)
			(stroke
				(width 0.1)
				(type default)
			)
			(layer "B.Fab")
		)
		(fp_line
			(start -0.120396 0.2794)
			(end 0.12065 0.2794)
			(stroke
				(width 0.1)
				(type default)
			)
			(layer "B.Fab")
		)
		(fp_line
			(start 0.67945 0.3048)
			(end 0.67945 -0.305054)
			(stroke
				(width 0.1)
				(type default)
			)
			(layer "B.Fab")
		)
		(fp_line
			(start 0.12065 0.3048)
			(end 0.67945 0.3048)
			(stroke
				(width 0.1)
				(type default)
			)
			(layer "B.Fab")
		)
		(fp_line
			(start -0.120396 0.3048)
			(end -0.120396 0.2794)
			(stroke
				(width 0.1)
				(type default)
			)
			(layer "B.Fab")
		)
		(fp_line
			(start -0.67945 0.3048)
			(end -0.120396 0.3048)
			(stroke
				(width 0.1)
				(type default)
			)
			(layer "B.Fab")
		)
		(pad "1" smd circle
			(at 0.40005 0 270)
			(size 0 0)
			(layers "B.Cu" "B.Mask" "B.Paste")
			(net "SMB_CPU0_CPU1_SEC_SDA")
		)
		(pad "2" smd circle
			(at -0.40005 0 270)
			(size 0 0)
			(layers "B.Cu" "B.Mask" "B.Paste")
			(net "P3V3_AUX")
		)
	)
	(footprint ""
		(layer "B.Cu")
		(at 175.641 -100.294948 -90)
		(property "Reference" "R204"
			(at 0 0 90)
			(layer "B.SilkS")
			(hide yes)
			(effects
				(font
					(size 1.27 1.27)
				)
				(justify mirror)
			)
		)
		(property "Value" ""
			(at 0 0 90)
			(layer "B.Fab")
			(effects
				(font
					(size 1.27 1.27)
				)
				(justify mirror)
			)
		)
		(duplicate_pad_numbers_are_jumpers no)
		(fp_line
			(start -0.7874 0.4064)
			(end 0.7874 0.4064)
			(stroke
				(width 0.1524)
				(type default)
			)
			(layer "B.SilkS")
		)
		(fp_line
			(start 0.7874 0.4064)
			(end 0.7874 -0.4064)
			(stroke
				(width 0.1524)
				(type default)
			)
			(layer "B.SilkS")
		)
		(fp_line
			(start -0.7874 -0.4064)
			(end -0.7874 0.4064)
			(stroke
				(width 0.1524)
				(type default)
			)
			(layer "B.SilkS")
		)
		(fp_line
			(start 0.7874 -0.4064)
			(end -0.7874 -0.4064)
			(stroke
				(width 0.1524)
				(type default)
			)
			(layer "B.SilkS")
		)
		(fp_line
			(start -0.67945 0.3048)
			(end -0.120396 0.3048)
			(stroke
				(width 0.1)
				(type default)
			)
			(layer "B.Fab")
		)
		(fp_line
			(start -0.120396 0.3048)
			(end -0.120396 0.2794)
			(stroke
				(width 0.1)
				(type default)
			)
			(layer "B.Fab")
		)
		(fp_line
			(start 0.12065 0.3048)
			(end 0.67945 0.3048)
			(stroke
				(width 0.1)
				(type default)
			)
			(layer "B.Fab")
		)
		(fp_line
			(start 0.67945 0.3048)
			(end 0.67945 -0.305054)
			(stroke
				(width 0.1)
				(type default)
			)
			(layer "B.Fab")
		)
		(fp_line
			(start -0.120396 0.2794)
			(end 0.12065 0.2794)
			(stroke
				(width 0.1)
				(type default)
			)
			(layer "B.Fab")
		)
		(fp_line
			(start 0.12065 0.2794)
			(end 0.12065 0.3048)
			(stroke
				(width 0.1)
				(type default)
			)
			(layer "B.Fab")
		)
		(fp_line
			(start -0.12065 -0.2794)
			(end -0.12065 -0.3048)
			(stroke
				(width 0.1)
				(type default)
			)
			(layer "B.Fab")
		)
		(fp_line
			(start 0.12065 -0.2794)
			(end -0.12065 -0.2794)
			(stroke
				(width 0.1)
				(type default)
			)
			(layer "B.Fab")
		)
		(fp_line
			(start -0.67945 -0.3048)
			(end -0.67945 0.3048)
			(stroke
				(width 0.1)
				(type default)
			)
			(layer "B.Fab")
		)
		(fp_line
			(start -0.12065 -0.3048)
			(end -0.67945 -0.3048)
			(stroke
				(width 0.1)
				(type default)
			)
			(layer "B.Fab")
		)
		(fp_line
			(start 0.12065 -0.305054)
			(end 0.12065 -0.2794)
			(stroke
				(width 0.1)
				(type default)
			)
			(layer "B.Fab")
		)
		(fp_line
			(start 0.67945 -0.305054)
			(end 0.12065 -0.305054)
			(stroke
				(width 0.1)
				(type default)
			)
			(layer "B.Fab")
		)
		(pad "1" smd circle
			(at 0.40005 0 90)
			(size 0 0)
			(layers "B.Cu" "B.Mask" "B.Paste")
			(net "CPU1_XTRIG_L4")
		)
		(pad "2" smd circle
			(at -0.40005 0 90)
			(size 0 0)
			(layers "B.Cu" "B.Mask" "B.Paste")
			(net "FM_CPU1_XTRIG_L4")
		)
	)
	(footprint ""
		(layer "B.Cu")
		(at 368.892836 -191.32423 90)
		(property "Reference" "PC501_2"
			(at 0 0 90)
			(layer "B.SilkS")
			(hide yes)
			(effects
				(font
					(size 1.27 1.27)
				)
				(justify mirror)
			)
		)
		(property "Value" ""
			(at 0 0 90)
			(layer "B.Fab")
			(effects
				(font
					(size 1.27 1.27)
				)
				(justify mirror)
			)
		)
		(duplicate_pad_numbers_are_jumpers no)
		(fp_line
			(start 1.524 -0.762)
			(end -1.524 -0.762)
			(stroke
				(width 0.1524)
				(type default)
			)
			(layer "B.SilkS")
		)
		(fp_line
			(start -1.524 -0.762)
			(end -1.524 0.762)
			(stroke
				(width 0.1524)
				(type default)
			)
			(layer "B.SilkS")
		)
		(fp_line
			(start 1.524 0.762)
			(end 1.524 -0.762)
			(stroke
				(width 0.1524)
				(type default)
			)
			(layer "B.SilkS")
		)
		(fp_line
			(start -1.524 0.762)
			(end 1.524 0.762)
			(stroke
				(width 0.1524)
				(type default)
			)
			(layer "B.SilkS")
		)
		(fp_line
			(start 1.1049 -0.724916)
			(end 1.1049 0.724916)
			(stroke
				(width 0.1)
				(type default)
			)
			(layer "B.Fab")
		)
		(fp_line
			(start -1.1049 -0.724916)
			(end 1.1049 -0.724916)
			(stroke
				(width 0.1)
				(type default)
			)
			(layer "B.Fab")
		)
		(fp_line
			(start 1.1049 0.724916)
			(end -1.1049 0.724916)
			(stroke
				(width 0.1)
				(type default)
			)
			(layer "B.Fab")
		)
		(fp_line
			(start -1.1049 0.724916)
			(end -1.1049 -0.724916)
			(stroke
				(width 0.1)
				(type default)
			)
			(layer "B.Fab")
		)
		(pad "1" smd rect
			(at 0.889 0 90)
			(size 1.016 1.27)
			(layers "B.Cu" "B.Mask" "B.Paste")
			(net "PVDDCR_CPU0_P0")
		)
		(pad "2" smd rect
			(at -0.889 0 90)
			(size 1.016 1.27)
			(layers "B.Cu" "B.Mask" "B.Paste")
			(net "GND")
		)
	)
	(footprint ""
		(layer "B.Cu")
		(at 183.132476 -117.842792)
		(property "Reference" "C1129"
			(at 0 0 0)
			(layer "B.SilkS")
			(hide yes)
			(effects
				(font
					(size 1.27 1.27)
				)
				(justify mirror)
			)
		)
		(property "Value" ""
			(at 0 0 0)
			(layer "B.Fab")
			(effects
				(font
					(size 1.27 1.27)
				)
				(justify mirror)
			)
		)
		(duplicate_pad_numbers_are_jumpers no)
		(fp_line
			(start -0.69215 -0.2921)
			(end -0.69215 0.2921)
			(stroke
				(width 0.1524)
				(type default)
			)
			(layer "B.SilkS")
		)
		(fp_line
			(start -0.69215 0.2921)
			(end 0.69215 0.2921)
			(stroke
				(width 0.1524)
				(type default)
			)
			(layer "B.SilkS")
		)
		(fp_line
			(start 0.69215 -0.2921)
			(end -0.69215 -0.2921)
			(stroke
				(width 0.1524)
				(type default)
			)
			(layer "B.SilkS")
		)
		(fp_line
			(start 0.69215 0.2921)
			(end 0.69215 -0.2921)
			(stroke
				(width 0.1524)
				(type default)
			)
			(layer "B.SilkS")
		)
		(fp_line
			(start -0.51435 -0.2794)
			(end -0.51435 0.2794)
			(stroke
				(width 0.1)
				(type default)
			)
			(layer "B.Fab")
		)
		(fp_line
			(start -0.51435 0.2794)
			(end 0.51435 0.2794)
			(stroke
				(width 0.1)
				(type default)
			)
			(layer "B.Fab")
		)
		(fp_line
			(start 0.51435 -0.2794)
			(end -0.51435 -0.2794)
			(stroke
				(width 0.1)
				(type default)
			)
			(layer "B.Fab")
		)
		(fp_line
			(start 0.51435 0.2794)
			(end 0.51435 -0.2794)
			(stroke
				(width 0.1)
				(type default)
			)
			(layer "B.Fab")
		)
		(pad "1" smd circle
			(at 0.40005 0 180)
			(size 0 0)
			(layers "B.Cu" "B.Mask" "B.Paste")
			(net "P1V8_AUX")
		)
		(pad "2" smd circle
			(at -0.40005 0 180)
			(size 0 0)
			(layers "B.Cu" "B.Mask" "B.Paste")
			(net "GND")
		)
		(zone
			(layer "B.Cu")
			(hatch none 0.5)
			(connect_pads
				(clearance 0)
			)
			(min_thickness 0.25)
			(keepout
				(tracks not_allowed)
				(vias allowed)
				(pads allowed)
				(copperpour not_allowed)
				(footprints allowed)
			)
			(placement
				(enabled no)
				(sheetname "")
			)
			(fill
				(thermal_gap 0.5)
				(thermal_bridge_width 0.5)
				(island_removal_mode 0)
			)
			(polygon
				(pts
					(xy 182.941976 -117.755162) (xy 182.941976 -117.930422) (xy 183.032146 -117.988842) (xy 183.231536 -117.988842)
					(xy 183.322976 -117.930676) (xy 183.322976 -117.755162) (xy 183.231536 -117.696996) (xy 183.032146 -117.696996)
				)
			)
		)
	)
	(footprint ""
		(layer "B.Cu")
		(at 254.635 -336.25536 180)
		(property "Reference" "R1379"
			(at 0 0 0)
			(layer "B.SilkS")
			(hide yes)
			(effects
				(font
					(size 1.27 1.27)
				)
				(justify mirror)
			)
		)
		(property "Value" ""
			(at 0 0 0)
			(layer "B.Fab")
			(effects
				(font
					(size 1.27 1.27)
				)
				(justify mirror)
			)
		)
		(duplicate_pad_numbers_are_jumpers no)
		(fp_line
			(start 0.32512 0.175006)
			(end 0.32512 -0.175006)
			(stroke
				(width 0.1)
				(type default)
			)
			(layer "B.Fab")
		)
		(fp_line
			(start 0.32512 -0.175006)
			(end -0.32512 -0.175006)
			(stroke
				(width 0.1)
				(type default)
			)
			(layer "B.Fab")
		)
		(fp_line
			(start -0.32512 0.175006)
			(end 0.32512 0.175006)
			(stroke
				(width 0.1)
				(type default)
			)
			(layer "B.Fab")
		)
		(fp_line
			(start -0.32512 -0.175006)
			(end -0.32512 0.175006)
			(stroke
				(width 0.1)
				(type default)
			)
			(layer "B.Fab")
		)
		(pad "1" smd rect
			(at 0.2667 0)
			(size 0.3048 0.381)
			(layers "B.Cu" "B.Mask" "B.Paste")
			(net "P1V8_CPU0_RT_1D")
		)
		(pad "2" smd rect
			(at -0.2667 0 180)
			(size 0.3048 0.381)
			(layers "B.Cu" "B.Mask" "B.Paste")
			(net "SMB_RT_CPU0_P3_ROM_MUX_2D_R_SCL")
		)
	)
	(footprint ""
		(layer "B.Cu")
		(at 118.078504 -386.766562 90)
		(property "Reference" "C497"
			(at 0 0 90)
			(layer "B.SilkS")
			(hide yes)
			(effects
				(font
					(size 1.27 1.27)
				)
				(justify mirror)
			)
		)
		(property "Value" ""
			(at 0 0 90)
			(layer "B.Fab")
			(effects
				(font
					(size 1.27 1.27)
				)
				(justify mirror)
			)
		)
		(duplicate_pad_numbers_are_jumpers no)
		(fp_line
			(start 0.299974 -0.150114)
			(end -0.299974 -0.150114)
			(stroke
				(width 0.1)
				(type default)
			)
			(layer "B.Fab")
		)
		(fp_line
			(start -0.299974 -0.150114)
			(end -0.299974 0.150114)
			(stroke
				(width 0.1)
				(type default)
			)
			(layer "B.Fab")
		)
		(fp_line
			(start 0.299974 0.150114)
			(end 0.299974 -0.150114)
			(stroke
				(width 0.1)
				(type default)
			)
			(layer "B.Fab")
		)
		(fp_line
			(start -0.299974 0.150114)
			(end 0.299974 0.150114)
			(stroke
				(width 0.1)
				(type default)
			)
			(layer "B.Fab")
		)
		(pad "1" smd rect
			(at 0.2667 0 270)
			(size 0.3048 0.381)
			(layers "B.Cu" "B.Mask" "B.Paste")
			(net "P0V9_CPU1_RT3_2A")
		)
		(pad "2" smd rect
			(at -0.2667 0 270)
			(size 0.3048 0.381)
			(layers "B.Cu" "B.Mask" "B.Paste")
			(net "GND")
		)
	)
	(footprint ""
		(layer "B.Cu")
		(at 333.783686 -416.899344 90)
		(property "Reference" "C6551"
			(at 0 0 90)
			(layer "B.SilkS")
			(hide yes)
			(effects
				(font
					(size 1.27 1.27)
				)
				(justify mirror)
			)
		)
		(property "Value" ""
			(at 0 0 90)
			(layer "B.Fab")
			(effects
				(font
					(size 1.27 1.27)
				)
				(justify mirror)
			)
		)
		(duplicate_pad_numbers_are_jumpers no)
		(fp_line
			(start 0.299974 -0.150114)
			(end -0.299974 -0.150114)
			(stroke
				(width 0.1)
				(type default)
			)
			(layer "B.Fab")
		)
		(fp_line
			(start -0.299974 -0.150114)
			(end -0.299974 0.150114)
			(stroke
				(width 0.1)
				(type default)
			)
			(layer "B.Fab")
		)
		(fp_line
			(start 0.299974 0.150114)
			(end 0.299974 -0.150114)
			(stroke
				(width 0.1)
				(type default)
			)
			(layer "B.Fab")
		)
		(fp_line
			(start -0.299974 0.150114)
			(end 0.299974 0.150114)
			(stroke
				(width 0.1)
				(type default)
			)
			(layer "B.Fab")
		)
		(pad "1" smd rect
			(at 0.2667 0 270)
			(size 0.3048 0.381)
			(layers "B.Cu" "B.Mask" "B.Paste")
			(net "P5E_CPU0_P1_TX_BUF_C_DP<9>")
		)
		(pad "2" smd rect
			(at -0.2667 0 270)
			(size 0.3048 0.381)
			(layers "B.Cu" "B.Mask" "B.Paste")
			(net "P5E_CPU0_P1_TX_BUF_DP<9>")
		)
	)
	(footprint ""
		(layer "B.Cu")
		(at 181.297834 -421.37711 -90)
		(property "Reference" "R9020"
			(at 0 0 90)
			(layer "B.SilkS")
			(hide yes)
			(effects
				(font
					(size 1.27 1.27)
				)
				(justify mirror)
			)
		)
		(property "Value" ""
			(at 0 0 90)
			(layer "B.Fab")
			(effects
				(font
					(size 1.27 1.27)
				)
				(justify mirror)
			)
		)
		(duplicate_pad_numbers_are_jumpers no)
		(fp_line
			(start -0.7874 0.4064)
			(end 0.7874 0.4064)
			(stroke
				(width 0.1524)
				(type default)
			)
			(layer "B.SilkS")
		)
		(fp_line
			(start 0.7874 0.4064)
			(end 0.7874 -0.4064)
			(stroke
				(width 0.1524)
				(type default)
			)
			(layer "B.SilkS")
		)
		(fp_line
			(start -0.7874 -0.4064)
			(end -0.7874 0.4064)
			(stroke
				(width 0.1524)
				(type default)
			)
			(layer "B.SilkS")
		)
		(fp_line
			(start 0.7874 -0.4064)
			(end -0.7874 -0.4064)
			(stroke
				(width 0.1524)
				(type default)
			)
			(layer "B.SilkS")
		)
		(fp_line
			(start -0.67945 0.3048)
			(end -0.120396 0.3048)
			(stroke
				(width 0.1)
				(type default)
			)
			(layer "B.Fab")
		)
		(fp_line
			(start -0.120396 0.3048)
			(end -0.120396 0.2794)
			(stroke
				(width 0.1)
				(type default)
			)
			(layer "B.Fab")
		)
		(fp_line
			(start 0.12065 0.3048)
			(end 0.67945 0.3048)
			(stroke
				(width 0.1)
				(type default)
			)
			(layer "B.Fab")
		)
		(fp_line
			(start 0.67945 0.3048)
			(end 0.67945 -0.305054)
			(stroke
				(width 0.1)
				(type default)
			)
			(layer "B.Fab")
		)
		(fp_line
			(start -0.120396 0.2794)
			(end 0.12065 0.2794)
			(stroke
				(width 0.1)
				(type default)
			)
			(layer "B.Fab")
		)
		(fp_line
			(start 0.12065 0.2794)
			(end 0.12065 0.3048)
			(stroke
				(width 0.1)
				(type default)
			)
			(layer "B.Fab")
		)
		(fp_line
			(start -0.12065 -0.2794)
			(end -0.12065 -0.3048)
			(stroke
				(width 0.1)
				(type default)
			)
			(layer "B.Fab")
		)
		(fp_line
			(start 0.12065 -0.2794)
			(end -0.12065 -0.2794)
			(stroke
				(width 0.1)
				(type default)
			)
			(layer "B.Fab")
		)
		(fp_line
			(start -0.67945 -0.3048)
			(end -0.67945 0.3048)
			(stroke
				(width 0.1)
				(type default)
			)
			(layer "B.Fab")
		)
		(fp_line
			(start -0.12065 -0.3048)
			(end -0.67945 -0.3048)
			(stroke
				(width 0.1)
				(type default)
			)
			(layer "B.Fab")
		)
		(fp_line
			(start 0.12065 -0.305054)
			(end 0.12065 -0.2794)
			(stroke
				(width 0.1)
				(type default)
			)
			(layer "B.Fab")
		)
		(fp_line
			(start 0.67945 -0.305054)
			(end 0.12065 -0.305054)
			(stroke
				(width 0.1)
				(type default)
			)
			(layer "B.Fab")
		)
		(pad "1" smd circle
			(at 0.40005 0 90)
			(size 0 0)
			(layers "B.Cu" "B.Mask" "B.Paste")
			(net "P3V3_AUX")
		)
		(pad "2" smd circle
			(at -0.40005 0 90)
			(size 0 0)
			(layers "B.Cu" "B.Mask" "B.Paste")
			(net "U142_VS")
		)
	)
	(footprint ""
		(layer "B.Cu")
		(at 72.908668 -177.513234 -90)
		(property "Reference" "PC311_5"
			(at 0 0 90)
			(layer "B.SilkS")
			(hide yes)
			(effects
				(font
					(size 1.27 1.27)
				)
				(justify mirror)
			)
		)
		(property "Value" ""
			(at 0 0 90)
			(layer "B.Fab")
			(effects
				(font
					(size 1.27 1.27)
				)
				(justify mirror)
			)
		)
		(duplicate_pad_numbers_are_jumpers no)
		(fp_line
			(start -1.524 0.762)
			(end 1.524 0.762)
			(stroke
				(width 0.1524)
				(type default)
			)
			(layer "B.SilkS")
		)
		(fp_line
			(start 1.524 0.762)
			(end 1.524 -0.762)
			(stroke
				(width 0.1524)
				(type default)
			)
			(layer "B.SilkS")
		)
		(fp_line
			(start -1.524 -0.762)
			(end -1.524 0.762)
			(stroke
				(width 0.1524)
				(type default)
			)
			(layer "B.SilkS")
		)
		(fp_line
			(start 1.524 -0.762)
			(end -1.524 -0.762)
			(stroke
				(width 0.1524)
				(type default)
			)
			(layer "B.SilkS")
		)
		(fp_line
			(start -1.1049 0.724916)
			(end -1.1049 -0.724916)
			(stroke
				(width 0.1)
				(type default)
			)
			(layer "B.Fab")
		)
		(fp_line
			(start 1.1049 0.724916)
			(end -1.1049 0.724916)
			(stroke
				(width 0.1)
				(type default)
			)
			(layer "B.Fab")
		)
		(fp_line
			(start -1.1049 -0.724916)
			(end 1.1049 -0.724916)
			(stroke
				(width 0.1)
				(type default)
			)
			(layer "B.Fab")
		)
		(fp_line
			(start 1.1049 -0.724916)
			(end 1.1049 0.724916)
			(stroke
				(width 0.1)
				(type default)
			)
			(layer "B.Fab")
		)
		(pad "1" smd rect
			(at 0.889 0 270)
			(size 1.016 1.27)
			(layers "B.Cu" "B.Mask" "B.Paste")
			(net "SW_P12V_AUX_PVDDCR_CPU0_P1_FLT")
		)
		(pad "2" smd rect
			(at -0.889 0 270)
			(size 1.016 1.27)
			(layers "B.Cu" "B.Mask" "B.Paste")
			(net "GND")
		)
	)
)
